(kicad_pcb
	(version 20260206)
	(generator "pcbnew")
	(generator_version "10.0")
	(general
		(thickness 1.6)
		(legacy_teardrops no)
	)
	(paper "A4")
	(title_block
		(title "Bryce Canyon_R.DPB_16317-1_OCP.brd")
		(comment 1 "Bryce Canyon / footprints 1232-1238 of 2099")
	)
	(layers
		(0 "F.Cu" signal "TOP")
		(4 "In1.Cu" signal "L2GND")
		(6 "In2.Cu" signal "L3")
		(8 "In3.Cu" signal "L4VCC")
		(10 "In4.Cu" signal "L5VCC")
		(12 "In5.Cu" signal "L6")
		(14 "In6.Cu" signal "L7GND")
		(2 "B.Cu" signal "BOTTOM")
		(9 "F.Adhes" user "F.Adhesive")
		(11 "B.Adhes" user "B.Adhesive")
		(13 "F.Paste" user "Package Geometry/Pastemask Top")
		(15 "B.Paste" user "Package Geometry/Pastemask Bottom")
		(5 "F.SilkS" user "Ref Des/Silkscreen Top")
		(7 "B.SilkS" user "Ref Des/Silkscreen Bottom")
		(1 "F.Mask" user "Board Geometry/Soldermask Top")
		(3 "B.Mask" user "Board Geometry/Soldermask Bottom")
		(17 "Dwgs.User" user "User.Drawings")
		(19 "Cmts.User" user "User.Comments")
		(21 "Eco1.User" user "User.Eco1")
		(23 "Eco2.User" user "User.Eco2")
		(25 "Edge.Cuts" user "Board Geometry/Outline")
		(27 "Margin" user)
		(31 "F.CrtYd" user "Package Geometry/Place Bound Top")
		(29 "B.CrtYd" user "Package Geometry/Place Bound Bottom")
		(35 "F.Fab" user "Ref Des/Assembly Top")
		(33 "B.Fab" user "Ref Des/Assembly Bottom")
	)
	(footprint ""
		(layer "F.Cu")
		(at 252.461268 -222.9612 180)
		(property "Reference" "R106"
			(at 0 0 180)
			(layer "F.SilkS")
			(hide yes)
			(effects
				(font
					(size 1.27 1.27)
				)
			)
		)
		(property "Value" "4K7R2F-GP"
			(at 0.064008 -3.993896 180)
			(unlocked yes)
			(layer "F.Fab")
			(hide yes)
			(effects
				(font
					(size 1.016 1.016)
					(thickness 0.1524)
				)
			)
		)
		(property "Device Type" "R402H16"
			(at 0.064008 -5.517896 180)
			(unlocked yes)
			(layer "F.Fab")
			(hide yes)
			(effects
				(font
					(size 1.016 1.016)
					(thickness 0.1524)
				)
			)
		)
		(duplicate_pad_numbers_are_jumpers no)
		(fp_line
			(start 0.508 -0.9398)
			(end -0.508 -0.9398)
			(stroke
				(width 0.1524)
				(type default)
			)
			(layer "F.SilkS")
		)
		(fp_line
			(start -0.508 -0.9398)
			(end -0.508 0.9398)
			(stroke
				(width 0.1524)
				(type default)
			)
			(layer "F.SilkS")
		)
		(fp_rect
			(start -0.508 0.9398)
			(end 0.508 -0.9398)
			(stroke
				(width 0)
				(type default)
			)
			(fill no)
			(layer "F.CrtYd")
		)
		(fp_rect
			(start -0.508 0.9398)
			(end 0.508 -0.9398)
			(stroke
				(width 0)
				(type default)
			)
			(fill no)
			(layer "F.Fab")
		)
		(pad "1" smd custom
			(at 0 -0.4445 180)
			(size 0.1397 0.1397)
			(layers "F.Cu" "F.Mask" "F.Paste")
			(net "EEPROM_A0")
			(options
				(clearance outline)
				(anchor circle)
			)
			(primitives
				(gr_poly
					(pts
						(arc
							(start -0.1778 -0.2794)
							(mid -0.249642 -0.249642)
							(end -0.2794 -0.1778)
						)
						(arc
							(start -0.2794 0.1778)
							(mid -0.249642 0.249642)
							(end -0.1778 0.2794)
						)
						(arc
							(start 0.1778 0.2794)
							(mid 0.249642 0.249642)
							(end 0.2794 0.1778)
						)
						(arc
							(start 0.2794 -0.1778)
							(mid 0.249642 -0.249642)
							(end 0.1778 -0.2794)
						)
					)
					(width 0)
					(fill yes)
				)
			)
		)
		(pad "2" smd custom
			(at 0 0.4445 180)
			(size 0.1397 0.1397)
			(layers "F.Cu" "F.Mask" "F.Paste")
			(net "GND")
			(options
				(clearance outline)
				(anchor circle)
			)
			(primitives
				(gr_poly
					(pts
						(arc
							(start -0.1778 -0.2794)
							(mid -0.249642 -0.249642)
							(end -0.2794 -0.1778)
						)
						(arc
							(start -0.2794 0.1778)
							(mid -0.249642 0.249642)
							(end -0.1778 0.2794)
						)
						(arc
							(start 0.1778 0.2794)
							(mid 0.249642 0.249642)
							(end 0.2794 0.1778)
						)
						(arc
							(start 0.2794 -0.1778)
							(mid 0.249642 -0.249642)
							(end 0.1778 -0.2794)
						)
					)
					(width 0)
					(fill yes)
				)
			)
		)
	)
	(footprint ""
		(layer "F.Cu")
		(at 209.03946 -166.41826 90)
		(property "Reference" "R57"
			(at 0 0 90)
			(layer "F.SilkS")
			(hide yes)
			(effects
				(font
					(size 1.27 1.27)
				)
			)
		)
		(property "Value" "4K7R2F-GP"
			(at 0.064008 -3.993896 90)
			(unlocked yes)
			(layer "F.Fab")
			(hide yes)
			(effects
				(font
					(size 1.016 1.016)
					(thickness 0.1524)
				)
			)
		)
		(property "Device Type" "R402H16"
			(at 0.064008 -5.517896 90)
			(unlocked yes)
			(layer "F.Fab")
			(hide yes)
			(effects
				(font
					(size 1.016 1.016)
					(thickness 0.1524)
				)
			)
		)
		(duplicate_pad_numbers_are_jumpers no)
		(fp_line
			(start 0.508 -0.9398)
			(end -0.508 -0.9398)
			(stroke
				(width 0.1524)
				(type default)
			)
			(layer "F.SilkS")
		)
		(fp_line
			(start -0.508 -0.9398)
			(end -0.508 0.9398)
			(stroke
				(width 0.1524)
				(type default)
			)
			(layer "F.SilkS")
		)
		(fp_rect
			(start -0.508 0.9398)
			(end 0.508 -0.9398)
			(stroke
				(width 0)
				(type default)
			)
			(fill no)
			(layer "F.CrtYd")
		)
		(fp_rect
			(start -0.508 0.9398)
			(end 0.508 -0.9398)
			(stroke
				(width 0)
				(type default)
			)
			(fill no)
			(layer "F.Fab")
		)
		(pad "1" smd custom
			(at 0 -0.4445 90)
			(size 0.1397 0.1397)
			(layers "F.Cu" "F.Mask" "F.Paste")
			(net "P3V3_STBY_B")
			(options
				(clearance outline)
				(anchor circle)
			)
			(primitives
				(gr_poly
					(pts
						(arc
							(start -0.1778 -0.2794)
							(mid -0.249642 -0.249642)
							(end -0.2794 -0.1778)
						)
						(arc
							(start -0.2794 0.1778)
							(mid -0.249642 0.249642)
							(end -0.1778 0.2794)
						)
						(arc
							(start 0.1778 0.2794)
							(mid 0.249642 0.249642)
							(end 0.2794 0.1778)
						)
						(arc
							(start 0.2794 -0.1778)
							(mid 0.249642 -0.249642)
							(end 0.1778 -0.2794)
						)
					)
					(width 0)
					(fill yes)
				)
			)
		)
		(pad "2" smd custom
			(at 0 0.4445 90)
			(size 0.1397 0.1397)
			(layers "F.Cu" "F.Mask" "F.Paste")
			(net "IO_EXP6_A0")
			(options
				(clearance outline)
				(anchor circle)
			)
			(primitives
				(gr_poly
					(pts
						(arc
							(start -0.1778 -0.2794)
							(mid -0.249642 -0.249642)
							(end -0.2794 -0.1778)
						)
						(arc
							(start -0.2794 0.1778)
							(mid -0.249642 0.249642)
							(end -0.1778 0.2794)
						)
						(arc
							(start 0.1778 0.2794)
							(mid 0.249642 0.249642)
							(end 0.2794 0.1778)
						)
						(arc
							(start 0.2794 -0.1778)
							(mid 0.249642 -0.249642)
							(end 0.1778 -0.2794)
						)
					)
					(width 0)
					(fill yes)
				)
			)
		)
	)
	(footprint ""
		(layer "F.Cu")
		(at 131.445 -372.179596)
		(property "Reference" "D39"
			(at 0 0 0)
			(layer "F.SilkS")
			(hide yes)
			(effects
				(font
					(size 1.27 1.27)
				)
			)
		)
		(property "Value" "BAS16H-GP"
			(at 0 -5.5372 0)
			(unlocked yes)
			(layer "F.Fab")
			(hide yes)
			(effects
				(font
					(size 1.016 1.016)
					(thickness 0.1524)
				)
			)
		)
		(property "Device Type" "SOD123AKH48"
			(at 0 -7.0612 0)
			(unlocked yes)
			(layer "F.Fab")
			(hide yes)
			(effects
				(font
					(size 1.016 1.016)
					(thickness 0.1524)
				)
			)
		)
		(duplicate_pad_numbers_are_jumpers no)
		(fp_line
			(start -1.016 -2.667)
			(end -1.016 2.667)
			(stroke
				(width 0.1524)
				(type default)
			)
			(layer "F.SilkS")
		)
		(fp_line
			(start -1.016 2.667)
			(end 1.016 2.667)
			(stroke
				(width 0.1524)
				(type default)
			)
			(layer "F.SilkS")
		)
		(fp_line
			(start 0.889 2.921)
			(end -0.889 2.921)
			(stroke
				(width 0.508)
				(type default)
			)
			(layer "F.SilkS")
		)
		(fp_line
			(start 1.016 -2.667)
			(end -1.016 -2.667)
			(stroke
				(width 0.1524)
				(type default)
			)
			(layer "F.SilkS")
		)
		(fp_line
			(start 1.016 2.667)
			(end 1.016 -2.667)
			(stroke
				(width 0.1524)
				(type default)
			)
			(layer "F.SilkS")
		)
		(fp_rect
			(start -1.143 3.175)
			(end 1.143 -2.794)
			(stroke
				(width 0)
				(type default)
			)
			(fill no)
			(layer "F.CrtYd")
		)
		(fp_poly
			(pts
				(xy -1.143 -2.794) (xy 1.143 -2.794) (xy 1.143 3.175) (xy -1.143 3.175)
			)
			(stroke
				(width 0)
				(type default)
			)
			(fill no)
			(layer "F.Fab")
		)
		(pad "A" smd rect
			(at 0 -1.6891)
			(size 0.889 1.397)
			(layers "F.Cu" "F.Mask" "F.Paste")
			(net "FAN_1_TACH0")
		)
		(pad "K" smd rect
			(at 0 1.6891)
			(size 0.889 1.397)
			(layers "F.Cu" "F.Mask" "F.Paste")
			(net "P12V_IN")
		)
	)
	(footprint ""
		(layer "F.Cu")
		(at 172.593 -260.858)
		(property "Reference" "Q20"
			(at 0 0 0)
			(layer "F.SilkS")
			(hide yes)
			(effects
				(font
					(size 1.27 1.27)
				)
			)
		)
		(property "Value" "AO4407AL-GP"
			(at -3.707384 -1.5367 0)
			(unlocked yes)
			(layer "F.Fab")
			(hide yes)
			(effects
				(font
					(size 1.016 1.016)
					(thickness 0.1524)
				)
			)
		)
		(property "Device Type" "SOIC8H69"
			(at -3.707384 -3.0607 0)
			(unlocked yes)
			(layer "F.Fab")
			(hide yes)
			(effects
				(font
					(size 1.016 1.016)
					(thickness 0.1524)
				)
			)
		)
		(duplicate_pad_numbers_are_jumpers no)
		(fp_line
			(start -2.7432 -1.4224)
			(end -2.7432 1.4224)
			(stroke
				(width 0.1524)
				(type default)
			)
			(layer "F.SilkS")
		)
		(fp_line
			(start -2.7432 1.4224)
			(end -2.6416 1.4224)
			(stroke
				(width 0.1524)
				(type default)
			)
			(layer "F.SilkS")
		)
		(fp_line
			(start -2.7432 1.4224)
			(end 2.1336 1.4224)
			(stroke
				(width 0.1524)
				(type default)
			)
			(layer "F.SilkS")
		)
		(fp_line
			(start -2.7178 -0.508)
			(end -2.1844 -0.0508)
			(stroke
				(width 0.1524)
				(type default)
			)
			(layer "F.SilkS")
		)
		(fp_line
			(start -2.6289 3.4417)
			(end -2.6289 1.4732)
			(stroke
				(width 0.381)
				(type default)
			)
			(layer "F.SilkS")
		)
		(fp_line
			(start -2.1844 -0.0508)
			(end -2.7178 0.508)
			(stroke
				(width 0.1524)
				(type default)
			)
			(layer "F.SilkS")
		)
		(fp_line
			(start 2.1336 -1.4224)
			(end -2.7432 -1.4224)
			(stroke
				(width 0.1524)
				(type default)
			)
			(layer "F.SilkS")
		)
		(fp_line
			(start 2.1336 1.4224)
			(end 2.1336 -1.4224)
			(stroke
				(width 0.1524)
				(type default)
			)
			(layer "F.SilkS")
		)
		(fp_poly
			(pts
				(xy -2.2098 -1.4224) (xy -2.2098 1.4224) (xy 2.2098 1.4224) (xy 2.2098 -1.4224)
			)
			(stroke
				(width 0)
				(type default)
			)
			(fill yes)
			(layer "F.SilkS")
		)
		(fp_rect
			(start -2.450084 2.999994)
			(end 2.450084 -2.999994)
			(stroke
				(width 0)
				(type default)
			)
			(fill no)
			(layer "F.CrtYd")
		)
		(fp_poly
			(pts
				(xy -2.8194 3.6322) (xy -2.8194 -3.6322) (xy 2.8194 -3.6322) (xy 2.8194 1.18364) (xy 2.450084 1.18364)
				(xy 2.450084 -2.999994) (xy -2.450084 -2.999994) (xy -2.450084 2.999994) (xy 2.450084 2.999994)
				(xy 2.450084 1.18618) (xy 2.8194 1.18618) (xy 2.8194 3.6322)
			)
			(stroke
				(width 0)
				(type default)
			)
			(fill no)
			(layer "F.CrtYd")
		)
		(fp_rect
			(start -2.8194 3.6322)
			(end 2.8194 -3.6322)
			(stroke
				(width 0)
				(type default)
			)
			(fill no)
			(layer "F.Fab")
		)
		(pad "1" smd rect
			(at -1.905 2.54)
			(size 0.635 1.651)
			(layers "F.Cu" "F.Mask" "F.Paste")
			(net "P12V_B")
		)
		(pad "2" smd rect
			(at -0.635 2.54)
			(size 0.635 1.651)
			(layers "F.Cu" "F.Mask" "F.Paste")
			(net "P12V_B")
		)
		(pad "3" smd rect
			(at 0.635 2.54)
			(size 0.635 1.651)
			(layers "F.Cu" "F.Mask" "F.Paste")
			(net "P12V_B")
		)
		(pad "4" smd rect
			(at 1.905 2.54)
			(size 0.635 1.651)
			(layers "F.Cu" "F.Mask" "F.Paste")
			(net "SW_HDD_N5")
		)
		(pad "5" smd rect
			(at 1.905 -2.54)
			(size 0.635 1.651)
			(layers "F.Cu" "F.Mask" "F.Paste")
			(net "P12V_HDD5")
		)
		(pad "6" smd rect
			(at 0.635 -2.54)
			(size 0.635 1.651)
			(layers "F.Cu" "F.Mask" "F.Paste")
			(net "P12V_HDD5")
		)
		(pad "7" smd rect
			(at -0.635 -2.54)
			(size 0.635 1.651)
			(layers "F.Cu" "F.Mask" "F.Paste")
			(net "P12V_HDD5")
		)
		(pad "8" smd rect
			(at -1.905 -2.54)
			(size 0.635 1.651)
			(layers "F.Cu" "F.Mask" "F.Paste")
			(net "P12V_HDD5")
		)
	)
	(footprint ""
		(layer "F.Cu")
		(at 330.67498 -293.799768)
		(property "Reference" ""
			(at 0 0 0)
			(layer "F.SilkS")
			(hide yes)
			(effects
				(font
					(size 1.27 1.27)
				)
			)
		)
		(property "Value" "*"
			(at -8.398764 -8.057642 0)
			(unlocked yes)
			(layer "F.Fab")
			(hide yes)
			(effects
				(font
					(size 1.016 1.016)
					(thickness 0.1524)
				)
			)
		)
		(duplicate_pad_numbers_are_jumpers no)
		(fp_poly
			(pts
				(arc
					(start 7.3152 0)
					(mid 0 7.3152)
					(end -7.3152 0)
				)
				(arc
					(start -7.3152 -5.9944)
					(mid 0 -13.3096)
					(end 7.3152 -5.9944)
				)
			)
			(stroke
				(width 0)
				(type default)
			)
			(fill no)
			(layer "B.CrtYd")
		)
		(fp_poly
			(pts
				(arc
					(start 7.3152 0)
					(mid 0 7.3152)
					(end -7.3152 0)
				)
				(arc
					(start -7.3152 -5.9944)
					(mid 0 -13.3096)
					(end 7.3152 -5.9944)
				)
			)
			(stroke
				(width 0)
				(type default)
			)
			(fill no)
			(layer "F.CrtYd")
		)
		(fp_poly
			(pts
				(arc
					(start 7.3152 0)
					(mid 0 7.3152)
					(end -7.3152 0)
				)
				(arc
					(start -7.3152 -5.9944)
					(mid 0 -13.3096)
					(end 7.3152 -5.9944)
				)
			)
			(stroke
				(width 0)
				(type default)
			)
			(fill no)
			(layer "B.Fab")
		)
		(fp_poly
			(pts
				(arc
					(start 7.3152 0)
					(mid 0 7.3152)
					(end -7.3152 0)
				)
				(arc
					(start -7.3152 -5.9944)
					(mid 0 -13.3096)
					(end 7.3152 -5.9944)
				)
			)
			(stroke
				(width 0)
				(type default)
			)
			(fill no)
			(layer "F.Fab")
		)
		(pad "1" thru_hole oval
			(at 0 0)
			(size 14.0208 20.0152)
			(drill 0.0254
				(offset 0 -2.9972)
			)
			(layers "*.Cu" "*.Mask")
			(remove_unused_layers no)
			(net "Net_40")
			(clearance -1.002284)
			(thermal_gap 0.1524)
			(padstack
				(mode front_inner_back)
				(layer "Inner"
					(shape custom)
					(size 2.928012 2.928012)
					(options
						(anchor circle)
					)
					(primitives
						(gr_poly
							(pts
								(arc
									(start 4.571746 -2.084324)
									(mid 0.000333 7.430372)
									(end -4.571492 -2.084324)
								)
								(arc
									(start -4.571492 -2.084324)
									(mid -3.570296 -3.611977)
									(end -2.875026 -5.30098)
								)
								(arc
									(start -2.875026 -5.30098)
									(mid 0.000217 -7.43089)
									(end 2.87528 -5.30098)
								)
								(arc
									(start 2.87528 -5.30098)
									(mid 3.570511 -3.611956)
									(end 4.571746 -2.084324)
								)
							)
							(width 0)
							(fill yes)
						)
					)
					(clearance 0.1524)
				)
				(layer "B.Cu"
					(shape oval)
					(size 14.0208 20.0152)
					(offset 0 -2.9972)
					(clearance -1.002284)
				)
			)
		)
		(zone
			(layers "F.Cu" "B.Cu" "In1.Cu" "In2.Cu" "In3.Cu" "In4.Cu" "In5.Cu" "In6.Cu")
			(hatch none 0.5)
			(connect_pads
				(clearance 0)
			)
			(min_thickness 0.25)
			(keepout
				(tracks not_allowed)
				(vias allowed)
				(pads allowed)
				(copperpour not_allowed)
				(footprints allowed)
			)
			(placement
				(enabled no)
				(sheetname "")
			)
			(fill
				(thermal_gap 0.5)
				(thermal_bridge_width 0.5)
				(island_removal_mode 0)
			)
			(polygon
				(pts
					(arc
						(start 323.66458 -299.794168)
						(mid 330.67498 -306.804568)
						(end 337.68538 -299.794168)
					)
					(arc
						(start 337.68538 -293.799768)
						(mid 330.67498 -286.789368)
						(end 323.66458 -293.799768)
					)
				)
			)
		)
	)
	(footprint ""
		(layer "F.Cu")
		(at 86.995 -157.226)
		(property "Reference" "C217"
			(at 0 0 0)
			(layer "F.SilkS")
			(hide yes)
			(effects
				(font
					(size 1.27 1.27)
				)
			)
		)
		(property "Value" "SC4D7U25V5KX-1-GP"
			(at -0.0762 -6.1214 0)
			(unlocked yes)
			(layer "F.Fab")
			(hide yes)
			(effects
				(font
					(size 1.016 1.016)
					(thickness 0.1524)
				)
			)
		)
		(property "Device Type" "C805H58"
			(at -0.0762 -8.1534 0)
			(unlocked yes)
			(layer "F.Fab")
			(hide yes)
			(effects
				(font
					(size 1.016 1.016)
					(thickness 0.1524)
				)
			)
		)
		(duplicate_pad_numbers_are_jumpers no)
		(fp_line
			(start 0.635 0)
			(end -0.635 0)
			(stroke
				(width 0.508)
				(type default)
			)
			(layer "F.SilkS")
		)
		(fp_rect
			(start -0.9652 1.778)
			(end 0.9652 -1.778)
			(stroke
				(width 0)
				(type default)
			)
			(fill no)
			(layer "F.CrtYd")
		)
		(fp_poly
			(pts
				(xy -0.9652 -1.778) (xy 0.9652 -1.778) (xy 0.9652 1.778) (xy -0.9652 1.778)
			)
			(stroke
				(width 0)
				(type default)
			)
			(fill no)
			(layer "F.Fab")
		)
		(pad "1" smd rect
			(at 0 -0.9652)
			(size 1.397 1.143)
			(layers "F.Cu" "F.Mask" "F.Paste")
			(net "P12V_HDD14")
		)
		(pad "2" smd rect
			(at 0 0.9652)
			(size 1.397 1.143)
			(layers "F.Cu" "F.Mask" "F.Paste")
			(net "GND")
		)
	)
	(footprint ""
		(layer "F.Cu")
		(at 241.8334 -131.6482 180)
		(property "Reference" "R604"
			(at 0 0 180)
			(layer "F.SilkS")
			(hide yes)
			(effects
				(font
					(size 1.27 1.27)
				)
			)
		)
		(property "Value" "2K2R2F-GP"
			(at 0.064008 -3.993896 180)
			(unlocked yes)
			(layer "F.Fab")
			(hide yes)
			(effects
				(font
					(size 1.016 1.016)
					(thickness 0.1524)
				)
			)
		)
		(property "Device Type" "R402H16"
			(at 0.064008 -5.517896 180)
			(unlocked yes)
			(layer "F.Fab")
			(hide yes)
			(effects
				(font
					(size 1.016 1.016)
					(thickness 0.1524)
				)
			)
		)
		(duplicate_pad_numbers_are_jumpers no)
		(fp_line
			(start 0.508 -0.9398)
			(end -0.508 -0.9398)
			(stroke
				(width 0.1524)
				(type default)
			)
			(layer "F.SilkS")
		)
		(fp_line
			(start -0.508 -0.9398)
			(end -0.508 0.9398)
			(stroke
				(width 0.1524)
				(type default)
			)
			(layer "F.SilkS")
		)
		(fp_rect
			(start -0.508 0.9398)
			(end 0.508 -0.9398)
			(stroke
				(width 0)
				(type default)
			)
			(fill no)
			(layer "F.CrtYd")
		)
		(fp_rect
			(start -0.508 0.9398)
			(end 0.508 -0.9398)
			(stroke
				(width 0)
				(type default)
			)
			(fill no)
			(layer "F.Fab")
		)
		(pad "1" smd custom
			(at 0 -0.4445 180)
			(size 0.1397 0.1397)
			(layers "F.Cu" "F.Mask" "F.Paste")
			(net "P3V3_STBY_B")
			(options
				(clearance outline)
				(anchor circle)
			)
			(primitives
				(gr_poly
					(pts
						(arc
							(start -0.1778 -0.2794)
							(mid -0.249642 -0.249642)
							(end -0.2794 -0.1778)
						)
						(arc
							(start -0.2794 0.1778)
							(mid -0.249642 0.249642)
							(end -0.1778 0.2794)
						)
						(arc
							(start 0.1778 0.2794)
							(mid 0.249642 0.249642)
							(end 0.2794 0.1778)
						)
						(arc
							(start 0.2794 -0.1778)
							(mid 0.249642 -0.249642)
							(end 0.1778 -0.2794)
						)
					)
					(width 0)
					(fill yes)
				)
			)
		)
		(pad "2" smd custom
			(at 0 0.4445 180)
			(size 0.1397 0.1397)
			(layers "F.Cu" "F.Mask" "F.Paste")
			(net "I2C_DPB_B_SCL")
			(options
				(clearance outline)
				(anchor circle)
			)
			(primitives
				(gr_poly
					(pts
						(arc
							(start -0.1778 -0.2794)
							(mid -0.249642 -0.249642)
							(end -0.2794 -0.1778)
						)
						(arc
							(start -0.2794 0.1778)
							(mid -0.249642 0.249642)
							(end -0.1778 0.2794)
						)
						(arc
							(start 0.1778 0.2794)
							(mid 0.249642 0.249642)
							(end 0.2794 0.1778)
						)
						(arc
							(start 0.2794 -0.1778)
							(mid 0.249642 -0.249642)
							(end 0.1778 -0.2794)
						)
					)
					(width 0)
					(fill yes)
				)
			)
		)
	)
)
